# S9S_MB_2U (Grand Teton) — schematic netlist excerpt (pin names and nets, part order shuffled) for the footprints in the layout excerpt that follows; sources: Cadence DE-HDL packaged netlist, KiCad conversion of 03242023_DA0F0TMBIJ0_F0T_Motherboard_J_brd_V01_OCP.brd

H89  HOLE  EMPTY  pkg TH  page 311 : \1\ = GND
C425  Q_CAP  22UF 4V 20% X6S  pkg C0402  page 77 : A = PVCCD_HV_CPU1 ; B = GND

(kicad_pcb
	(version 20260206)
	(generator "pcbnew")
	(generator_version "10.0")
	(general
		(thickness 1.6)
		(legacy_teardrops no)
	)
	(paper "A4")
	(title_block
		(title "03242023_DA0F0TMBIJ0_F0T_Motherboard_J_brd_V01_OCP.brd")
		(comment 1 "Grand Teton / footprints 345-346 of 6105")
	)
	(layers
		(0 "F.Cu" signal "TOP")
		(4 "In1.Cu" signal "GND")
		(6 "In2.Cu" signal "IN1")
		(8 "In3.Cu" signal "GND1")
		(10 "In4.Cu" signal "IN2")
		(12 "In5.Cu" signal "GND2")
		(14 "In6.Cu" signal "IN3")
		(16 "In7.Cu" signal "GND3")
		(18 "In8.Cu" signal "VCC")
		(20 "In9.Cu" signal "VCC1")
		(22 "In10.Cu" signal "GND4")
		(24 "In11.Cu" signal "IN4")
		(26 "In12.Cu" signal "GND5")
		(28 "In13.Cu" signal "IN5")
		(30 "In14.Cu" signal "GND6")
		(32 "In15.Cu" signal "IN6")
		(34 "In16.Cu" signal "GND7")
		(2 "B.Cu" signal "BOTTOM")
		(9 "F.Adhes" user "F.Adhesive")
		(11 "B.Adhes" user "B.Adhesive")
		(13 "F.Paste" user "Package Geometry/Pastemask Top")
		(15 "B.Paste" user "Package Geometry/Pastemask Bottom")
		(5 "F.SilkS" user "Ref Des/Silkscreen Top")
		(7 "B.SilkS" user "Ref Des/Silkscreen Bottom")
		(1 "F.Mask" user "Board Geometry/Soldermask Top")
		(3 "B.Mask" user "Board Geometry/Soldermask Bottom")
		(17 "Dwgs.User" user "User.Drawings")
		(19 "Cmts.User" user "User.Comments")
		(21 "Eco1.User" user "User.Eco1")
		(23 "Eco2.User" user "User.Eco2")
		(25 "Edge.Cuts" user "Board Geometry/Outline")
		(27 "Margin" user)
		(31 "F.CrtYd" user "Package Geometry/Place Bound Top")
		(29 "B.CrtYd" user "Package Geometry/Place Bound Bottom")
		(35 "F.Fab" user "Ref Des/Assembly Top")
		(33 "B.Fab" user "Ref Des/Assembly Bottom")
	)
	(footprint ""
		(layer "F.Cu")
		(at 104.361234 -247.715278 90)
		(property "Reference" "C425"
			(at 0 0 90)
			(layer "F.SilkS")
			(hide yes)
			(effects
				(font
					(size 1.27 1.27)
				)
			)
		)
		(property "Value" ""
			(at 0 0 90)
			(layer "F.Fab")
			(effects
				(font
					(size 1.27 1.27)
				)
			)
		)
		(duplicate_pad_numbers_are_jumpers no)
		(fp_line
			(start 0.7874 -0.4064)
			(end 0.7874 0.4064)
			(stroke
				(width 0.1524)
				(type default)
			)
			(layer "F.SilkS")
		)
		(fp_line
			(start -0.7874 -0.4064)
			(end 0.7874 -0.4064)
			(stroke
				(width 0.1524)
				(type default)
			)
			(layer "F.SilkS")
		)
		(fp_line
			(start 0.7874 0.4064)
			(end -0.7874 0.4064)
			(stroke
				(width 0.1524)
				(type default)
			)
			(layer "F.SilkS")
		)
		(fp_line
			(start -0.7874 0.4064)
			(end -0.7874 -0.4064)
			(stroke
				(width 0.1524)
				(type default)
			)
			(layer "F.SilkS")
		)
		(fp_line
			(start -0.12065 -0.305054)
			(end -0.12065 -0.2794)
			(stroke
				(width 0.1)
				(type default)
			)
			(layer "F.Fab")
		)
		(fp_line
			(start -0.67945 -0.305054)
			(end -0.12065 -0.305054)
			(stroke
				(width 0.1)
				(type default)
			)
			(layer "F.Fab")
		)
		(fp_line
			(start 0.67945 -0.3048)
			(end 0.67945 0.3048)
			(stroke
				(width 0.1)
				(type default)
			)
			(layer "F.Fab")
		)
		(fp_line
			(start 0.12065 -0.3048)
			(end 0.67945 -0.3048)
			(stroke
				(width 0.1)
				(type default)
			)
			(layer "F.Fab")
		)
		(fp_line
			(start 0.12065 -0.2794)
			(end 0.12065 -0.3048)
			(stroke
				(width 0.1)
				(type default)
			)
			(layer "F.Fab")
		)
		(fp_line
			(start -0.12065 -0.2794)
			(end 0.12065 -0.2794)
			(stroke
				(width 0.1)
				(type default)
			)
			(layer "F.Fab")
		)
		(fp_line
			(start 0.120396 0.2794)
			(end -0.12065 0.2794)
			(stroke
				(width 0.1)
				(type default)
			)
			(layer "F.Fab")
		)
		(fp_line
			(start -0.12065 0.2794)
			(end -0.12065 0.3048)
			(stroke
				(width 0.1)
				(type default)
			)
			(layer "F.Fab")
		)
		(fp_line
			(start 0.67945 0.3048)
			(end 0.120396 0.3048)
			(stroke
				(width 0.1)
				(type default)
			)
			(layer "F.Fab")
		)
		(fp_line
			(start 0.120396 0.3048)
			(end 0.120396 0.2794)
			(stroke
				(width 0.1)
				(type default)
			)
			(layer "F.Fab")
		)
		(fp_line
			(start -0.12065 0.3048)
			(end -0.67945 0.3048)
			(stroke
				(width 0.1)
				(type default)
			)
			(layer "F.Fab")
		)
		(fp_line
			(start -0.67945 0.3048)
			(end -0.67945 -0.305054)
			(stroke
				(width 0.1)
				(type default)
			)
			(layer "F.Fab")
		)
		(pad "1" smd circle
			(at -0.40005 0 90)
			(size 0 0)
			(layers "F.Cu" "F.Mask" "F.Paste")
			(net "PVCCD_HV_CPU1")
		)
		(pad "2" smd circle
			(at 0.40005 0 90)
			(size 0 0)
			(layers "F.Cu" "F.Mask" "F.Paste")
			(net "GND")
		)
	)
	(footprint ""
		(layer "F.Cu")
		(at 179.749958 -435.600094)
		(property "Reference" "H89"
			(at -5.998718 -4.288536 0)
			(unlocked yes)
			(layer "F.SilkS")
			(effects
				(font
					(size 0.7874 0.5842)
					(thickness 0.1524)
				)
				(justify left)
			)
		)
		(property "Value" ""
			(at 0 0 0)
			(layer "F.Fab")
			(effects
				(font
					(size 1.27 1.27)
				)
			)
		)
		(duplicate_pad_numbers_are_jumpers no)
		(pad "1" thru_hole circle
			(at 0 0)
			(size 10.0076 10.0076)
			(drill 5.6134)
			(layers "*.Cu" "*.Mask")
			(remove_unused_layers no)
			(net "GND")
			(clearance -1.9431)
		)
	)
)
